# T6G (Grand Teton) — schematic netlist excerpt (pin names and nets, part order shuffled) for the footprints in the layout excerpt that follows; sources: Cadence DE-HDL packaged netlist, KiCad conversion of 04192023_DAF0TMB3IC0_F0TG_MB_C_brd_V02_OCP.brd

PD103  SCHOTTKY_AC  B340A-13-F IC  pkg D2010XF  page 134 : A = GND ; C = P3V3_OCP_SFF_R
R8018  Q_RES  0 5% CHIP  pkg 0402LF  page 167 : A = P1V8_AUX ; B = U124_VCC

(kicad_pcb
	(version 20260206)
	(generator "pcbnew")
	(generator_version "10.0")
	(general
		(thickness 1.6)
		(legacy_teardrops no)
	)
	(paper "A4")
	(title_block
		(title "04192023_DAF0TMB3IC0_F0TG_MB_C_brd_V02_OCP.brd")
		(comment 1 "Grand Teton / footprints 745-746 of 8354")
	)
	(layers
		(0 "F.Cu" signal "TOP")
		(4 "In1.Cu" signal "GND")
		(6 "In2.Cu" signal "IN1")
		(8 "In3.Cu" signal "GND1")
		(10 "In4.Cu" signal "IN2")
		(12 "In5.Cu" signal "GND2")
		(14 "In6.Cu" signal "IN3")
		(16 "In7.Cu" signal "GND3")
		(18 "In8.Cu" signal "VCC")
		(20 "In9.Cu" signal "VCC1")
		(22 "In10.Cu" signal "GND4")
		(24 "In11.Cu" signal "IN4")
		(26 "In12.Cu" signal "GND5")
		(28 "In13.Cu" signal "IN5")
		(30 "In14.Cu" signal "GND6")
		(32 "In15.Cu" signal "IN6")
		(34 "In16.Cu" signal "GND7")
		(2 "B.Cu" signal "BOTTOM")
		(9 "F.Adhes" user "F.Adhesive")
		(11 "B.Adhes" user "B.Adhesive")
		(13 "F.Paste" user "Package Geometry/Pastemask Top")
		(15 "B.Paste" user "Package Geometry/Pastemask Bottom")
		(5 "F.SilkS" user "Ref Des/Silkscreen Top")
		(7 "B.SilkS" user "Ref Des/Silkscreen Bottom")
		(1 "F.Mask" user "Board Geometry/Soldermask Top")
		(3 "B.Mask" user "Board Geometry/Soldermask Bottom")
		(17 "Dwgs.User" user "User.Drawings")
		(19 "Cmts.User" user "User.Comments")
		(21 "Eco1.User" user "User.Eco1")
		(23 "Eco2.User" user "User.Eco2")
		(25 "Edge.Cuts" user "Board Geometry/Outline")
		(27 "Margin" user)
		(31 "F.CrtYd" user "Package Geometry/Place Bound Top")
		(29 "B.CrtYd" user "Package Geometry/Place Bound Bottom")
		(35 "F.Fab" user "Ref Des/Assembly Top")
		(33 "B.Fab" user "Ref Des/Assembly Bottom")
	)
	(footprint ""
		(layer "F.Cu")
		(at 422.623742 -97.941892)
		(property "Reference" "PD103"
			(at -2.246376 2.802382 0)
			(unlocked yes)
			(layer "F.SilkS")
			(effects
				(font
					(size 0.7874 0.5842)
					(thickness 0.1524)
				)
				(justify left)
			)
		)
		(property "Value" ""
			(at 0 0 0)
			(layer "F.Fab")
			(effects
				(font
					(size 1.27 1.27)
				)
			)
		)
		(duplicate_pad_numbers_are_jumpers no)
		(fp_line
			(start -3.400044 -1.459992)
			(end 4.107942 -1.459992)
			(stroke
				(width 0.1524)
				(type default)
			)
			(layer "F.SilkS")
		)
		(fp_line
			(start -3.400044 1.459992)
			(end -3.400044 -1.459992)
			(stroke
				(width 0.1524)
				(type default)
			)
			(layer "F.SilkS")
		)
		(fp_line
			(start 4.107942 -1.459992)
			(end 4.107942 1.459992)
			(stroke
				(width 0.1524)
				(type default)
			)
			(layer "F.SilkS")
		)
		(fp_line
			(start 4.107942 1.459992)
			(end -3.400044 1.459992)
			(stroke
				(width 0.1524)
				(type default)
			)
			(layer "F.SilkS")
		)
		(fp_rect
			(start 3.308096 1.459992)
			(end 4.107942 -1.459992)
			(stroke
				(width 0)
				(type default)
			)
			(fill yes)
			(layer "F.SilkS")
		)
		(fp_line
			(start -2.29997 -1.459992)
			(end 2.29997 -1.459992)
			(stroke
				(width 0.1)
				(type default)
			)
			(layer "F.Fab")
		)
		(fp_line
			(start -2.29997 1.459992)
			(end -2.29997 -1.459992)
			(stroke
				(width 0.1)
				(type default)
			)
			(layer "F.Fab")
		)
		(fp_line
			(start 2.29997 -1.459992)
			(end 2.29997 1.459992)
			(stroke
				(width 0.1)
				(type default)
			)
			(layer "F.Fab")
		)
		(fp_line
			(start 2.29997 1.459992)
			(end -2.29997 1.459992)
			(stroke
				(width 0.1)
				(type default)
			)
			(layer "F.Fab")
		)
		(fp_text user "+"
			(at -4.7752 -0.12065 0)
			(unlocked yes)
			(layer "F.SilkS")
			(effects
				(font
					(size 1.905 1.4224)
					(thickness 0.1524)
				)
				(justify left)
			)
		)
		(fp_text user "-"
			(at 4.51358 2.29997 180)
			(unlocked yes)
			(layer "F.SilkS")
			(effects
				(font
					(size 1.905 1.4224)
					(thickness 0.1524)
				)
				(justify left)
			)
		)
		(fp_text user "+"
			(at -4.7752 -0.12065 0)
			(unlocked yes)
			(layer "F.Fab")
			(effects
				(font
					(size 1.905 1.4224)
					(thickness 0.1524)
				)
				(justify left)
			)
		)
		(fp_text user "-"
			(at 5.4102 0.29845 180)
			(unlocked yes)
			(layer "F.Fab")
			(effects
				(font
					(size 1.905 1.4224)
					(thickness 0.1524)
				)
				(justify left)
			)
		)
		(pad "A" smd rect
			(at -1.999996 0 90)
			(size 1.7018 2.5146)
			(layers "F.Cu" "F.Mask" "F.Paste")
			(net "GND")
		)
		(pad "C" smd rect
			(at 1.999996 0 90)
			(size 1.7018 2.5146)
			(layers "F.Cu" "F.Mask" "F.Paste")
			(net "P3V3_OCP_SFF_R")
		)
	)
	(footprint ""
		(layer "F.Cu")
		(at 429.006 -58.42 -90)
		(property "Reference" "R8018"
			(at 0 0 270)
			(layer "F.SilkS")
			(hide yes)
			(effects
				(font
					(size 1.27 1.27)
				)
			)
		)
		(property "Value" ""
			(at 0 0 270)
			(layer "F.Fab")
			(effects
				(font
					(size 1.27 1.27)
				)
			)
		)
		(duplicate_pad_numbers_are_jumpers no)
		(fp_line
			(start -0.7874 0.4064)
			(end -0.7874 -0.4064)
			(stroke
				(width 0.1524)
				(type default)
			)
			(layer "F.SilkS")
		)
		(fp_line
			(start 0.7874 0.4064)
			(end -0.7874 0.4064)
			(stroke
				(width 0.1524)
				(type default)
			)
			(layer "F.SilkS")
		)
		(fp_line
			(start -0.7874 -0.4064)
			(end 0.7874 -0.4064)
			(stroke
				(width 0.1524)
				(type default)
			)
			(layer "F.SilkS")
		)
		(fp_line
			(start 0.7874 -0.4064)
			(end 0.7874 0.4064)
			(stroke
				(width 0.1524)
				(type default)
			)
			(layer "F.SilkS")
		)
		(fp_line
			(start -0.67945 0.3048)
			(end -0.67945 -0.305054)
			(stroke
				(width 0.1)
				(type default)
			)
			(layer "F.Fab")
		)
		(fp_line
			(start -0.12065 0.3048)
			(end -0.67945 0.3048)
			(stroke
				(width 0.1)
				(type default)
			)
			(layer "F.Fab")
		)
		(fp_line
			(start 0.120396 0.3048)
			(end 0.120396 0.2794)
			(stroke
				(width 0.1)
				(type default)
			)
			(layer "F.Fab")
		)
		(fp_line
			(start 0.67945 0.3048)
			(end 0.120396 0.3048)
			(stroke
				(width 0.1)
				(type default)
			)
			(layer "F.Fab")
		)
		(fp_line
			(start -0.12065 0.2794)
			(end -0.12065 0.3048)
			(stroke
				(width 0.1)
				(type default)
			)
			(layer "F.Fab")
		)
		(fp_line
			(start 0.120396 0.2794)
			(end -0.12065 0.2794)
			(stroke
				(width 0.1)
				(type default)
			)
			(layer "F.Fab")
		)
		(fp_line
			(start -0.12065 -0.2794)
			(end 0.12065 -0.2794)
			(stroke
				(width 0.1)
				(type default)
			)
			(layer "F.Fab")
		)
		(fp_line
			(start 0.12065 -0.2794)
			(end 0.12065 -0.3048)
			(stroke
				(width 0.1)
				(type default)
			)
			(layer "F.Fab")
		)
		(fp_line
			(start 0.12065 -0.3048)
			(end 0.67945 -0.3048)
			(stroke
				(width 0.1)
				(type default)
			)
			(layer "F.Fab")
		)
		(fp_line
			(start 0.67945 -0.3048)
			(end 0.67945 0.3048)
			(stroke
				(width 0.1)
				(type default)
			)
			(layer "F.Fab")
		)
		(fp_line
			(start -0.67945 -0.305054)
			(end -0.12065 -0.305054)
			(stroke
				(width 0.1)
				(type default)
			)
			(layer "F.Fab")
		)
		(fp_line
			(start -0.12065 -0.305054)
			(end -0.12065 -0.2794)
			(stroke
				(width 0.1)
				(type default)
			)
			(layer "F.Fab")
		)
		(pad "1" smd circle
			(at -0.40005 0 270)
			(size 0 0)
			(layers "F.Cu" "F.Mask" "F.Paste")
			(net "P1V8_AUX")
		)
		(pad "2" smd circle
			(at 0.40005 0 270)
			(size 0 0)
			(layers "F.Cu" "F.Mask" "F.Paste")
			(net "U124_VCC")
		)
	)
)
